(kicad_pcb
	(version 20260206)
	(generator "pcbnew")
	(generator_version "10.0")
	(general
		(thickness 1.6)
		(legacy_teardrops no)
	)
	(paper "A4")
	(title_block
		(title "panther-plus-userver — 13130-1b_20150205.brd")
		(comment 1 "Honey Badger (Wiwynn) / footprints 825-832 of 1509")
	)
	(layers
		(0 "F.Cu" signal "TOP")
		(4 "In1.Cu" signal "L2")
		(6 "In2.Cu" signal "L3")
		(8 "In3.Cu" signal "L4")
		(10 "In4.Cu" signal "L5")
		(12 "In5.Cu" signal "L6")
		(14 "In6.Cu" signal "L7")
		(16 "In7.Cu" signal "L8")
		(18 "In8.Cu" signal "L9")
		(20 "In9.Cu" signal "L10")
		(22 "In10.Cu" signal "L11")
		(2 "B.Cu" signal "BOTTOM")
		(9 "F.Adhes" user "F.Adhesive")
		(11 "B.Adhes" user "B.Adhesive")
		(13 "F.Paste" user "Package Geometry/Pastemask Top")
		(15 "B.Paste" user "Package Geometry/Pastemask Bottom")
		(5 "F.SilkS" user "Ref Des/Silkscreen Top")
		(7 "B.SilkS" user "Ref Des/Silkscreen Bottom")
		(1 "F.Mask" user "Board Geometry/Soldermask Top")
		(3 "B.Mask" user "Board Geometry/Soldermask Bottom")
		(17 "Dwgs.User" user "User.Drawings")
		(19 "Cmts.User" user "User.Comments")
		(21 "Eco1.User" user "User.Eco1")
		(23 "Eco2.User" user "User.Eco2")
		(25 "Edge.Cuts" user "Board Geometry/Outline")
		(27 "Margin" user)
		(31 "F.CrtYd" user "Package Geometry/Place Bound Top")
		(29 "B.CrtYd" user "Package Geometry/Place Bound Bottom")
		(35 "F.Fab" user "Ref Des/Assembly Top")
		(33 "B.Fab" user "Ref Des/Assembly Bottom")
	)
	(footprint ""
		(layer "B.Cu")
		(at 31.369 -42.545 180)
		(property "Reference" "PR187"
			(at 0 0 0)
			(layer "B.SilkS")
			(hide yes)
			(effects
				(font
					(size 1.27 1.27)
				)
				(justify mirror)
			)
		)
		(property "Value" "0R3J-6-GP"
			(at 0.0254 -2.0193 180)
			(unlocked yes)
			(layer "B.Fab")
			(hide yes)
			(effects
				(font
					(size 1.016 1.016)
					(thickness 0.1524)
				)
				(justify mirror)
			)
		)
		(property "Device Type" "R603H22"
			(at 0.0254 -3.5433 180)
			(unlocked yes)
			(layer "B.Fab")
			(hide yes)
			(effects
				(font
					(size 1.016 1.016)
					(thickness 0.1524)
				)
				(justify mirror)
			)
		)
		(duplicate_pad_numbers_are_jumpers no)
		(fp_line
			(start 0.2032 0)
			(end 0.4191 0)
			(stroke
				(width 0.2032)
				(type default)
			)
			(layer "B.SilkS")
		)
		(fp_line
			(start -0.4318 0)
			(end -0.2032 0)
			(stroke
				(width 0.2032)
				(type default)
			)
			(layer "B.SilkS")
		)
		(fp_rect
			(start 0.635 1.1811)
			(end -0.635 -1.1811)
			(stroke
				(width 0)
				(type default)
			)
			(fill no)
			(layer "B.CrtYd")
		)
		(fp_rect
			(start 0.635 1.1811)
			(end -0.635 -1.1811)
			(stroke
				(width 0)
				(type default)
			)
			(fill no)
			(layer "B.Fab")
		)
		(pad "1" smd custom
			(at 0 -0.6604)
			(size 0.19685 0.19685)
			(layers "B.Cu" "B.Mask" "B.Paste")
			(net "P1V5_STBY")
			(options
				(clearance outline)
				(anchor circle)
			)
			(primitives
				(gr_poly
					(pts
						(arc
							(start 0.508 0.2921)
							(mid 0.478242 0.363942)
							(end 0.4064 0.3937)
						)
						(arc
							(start -0.4064 0.3937)
							(mid -0.478242 0.363942)
							(end -0.508 0.2921)
						)
						(arc
							(start -0.508 -0.2921)
							(mid -0.478242 -0.363942)
							(end -0.4064 -0.3937)
						)
						(arc
							(start 0.4064 -0.3937)
							(mid 0.478242 -0.363942)
							(end 0.508 -0.2921)
						)
					)
					(width 0)
					(fill yes)
				)
			)
		)
		(pad "2" smd custom
			(at 0 0.6604)
			(size 0.19685 0.19685)
			(layers "B.Cu" "B.Mask" "B.Paste")
			(net "P1V5_STBY_OUT")
			(options
				(clearance outline)
				(anchor circle)
			)
			(primitives
				(gr_poly
					(pts
						(arc
							(start 0.508 0.2921)
							(mid 0.478242 0.363942)
							(end 0.4064 0.3937)
						)
						(arc
							(start -0.4064 0.3937)
							(mid -0.478242 0.363942)
							(end -0.508 0.2921)
						)
						(arc
							(start -0.508 -0.2921)
							(mid -0.478242 -0.363942)
							(end -0.4064 -0.3937)
						)
						(arc
							(start 0.4064 -0.3937)
							(mid 0.478242 -0.363942)
							(end 0.508 -0.2921)
						)
					)
					(width 0)
					(fill yes)
				)
			)
		)
	)
	(footprint ""
		(layer "B.Cu")
		(at 40.894 -51.943 180)
		(property "Reference" "C62"
			(at 0 0 0)
			(layer "B.SilkS")
			(hide yes)
			(effects
				(font
					(size 1.27 1.27)
				)
				(justify mirror)
			)
		)
		(property "Value" "SCD1U10V2KX-5GP"
			(at -1.8923 -1.2065 180)
			(unlocked yes)
			(layer "B.Fab")
			(hide yes)
			(effects
				(font
					(size 1.016 1.016)
					(thickness 0.1524)
				)
				(justify mirror)
			)
		)
		(property "Device Type" "C402H22"
			(at -1.8923 -2.7305 180)
			(unlocked yes)
			(layer "B.Fab")
			(hide yes)
			(effects
				(font
					(size 1.016 1.016)
					(thickness 0.1524)
				)
				(justify mirror)
			)
		)
		(duplicate_pad_numbers_are_jumpers no)
		(fp_rect
			(start 0.381 0.7366)
			(end -0.381 -0.7366)
			(stroke
				(width 0)
				(type default)
			)
			(fill no)
			(layer "B.CrtYd")
		)
		(fp_rect
			(start 0.381 0.7366)
			(end -0.381 -0.7366)
			(stroke
				(width 0)
				(type default)
			)
			(fill no)
			(layer "B.Fab")
		)
		(pad "1" smd custom
			(at 0 -0.4572)
			(size 0.1143 0.1143)
			(layers "B.Cu" "B.Mask" "B.Paste")
			(net "P3V3_CLK_PCI")
			(options
				(clearance outline)
				(anchor circle)
			)
			(primitives
				(gr_poly
					(pts
						(arc
							(start -0.254 0.1778)
							(mid -0.239121 0.213721)
							(end -0.2032 0.2286)
						)
						(arc
							(start 0.2032 0.2286)
							(mid 0.239121 0.213721)
							(end 0.254 0.1778)
						)
						(arc
							(start 0.254 -0.1778)
							(mid 0.239121 -0.213721)
							(end 0.2032 -0.2286)
						)
						(arc
							(start -0.2032 -0.2286)
							(mid -0.239121 -0.213721)
							(end -0.254 -0.1778)
						)
					)
					(width 0)
					(fill yes)
				)
			)
		)
		(pad "2" smd custom
			(at 0 0.4572)
			(size 0.1143 0.1143)
			(layers "B.Cu" "B.Mask" "B.Paste")
			(net "GND")
			(options
				(clearance outline)
				(anchor circle)
			)
			(primitives
				(gr_poly
					(pts
						(arc
							(start -0.254 0.1778)
							(mid -0.239121 0.213721)
							(end -0.2032 0.2286)
						)
						(arc
							(start 0.2032 0.2286)
							(mid 0.239121 0.213721)
							(end 0.254 0.1778)
						)
						(arc
							(start 0.254 -0.1778)
							(mid 0.239121 -0.213721)
							(end 0.2032 -0.2286)
						)
						(arc
							(start -0.2032 -0.2286)
							(mid -0.239121 -0.213721)
							(end -0.254 -0.1778)
						)
					)
					(width 0)
					(fill yes)
				)
			)
		)
	)
	(footprint ""
		(layer "B.Cu")
		(at 39.878 -65.278 90)
		(property "Reference" "PR11"
			(at 0 0 90)
			(layer "B.SilkS")
			(hide yes)
			(effects
				(font
					(size 1.27 1.27)
				)
				(justify mirror)
			)
		)
		(property "Value" "0R2J-2-GP"
			(at -1.7907 -1.1176 90)
			(unlocked yes)
			(layer "B.Fab")
			(hide yes)
			(effects
				(font
					(size 1.016 1.016)
					(thickness 0.1524)
				)
				(justify mirror)
			)
		)
		(property "Device Type" "R402H16"
			(at -1.7907 -2.6416 90)
			(unlocked yes)
			(layer "B.Fab")
			(hide yes)
			(effects
				(font
					(size 1.016 1.016)
					(thickness 0.1524)
				)
				(justify mirror)
			)
		)
		(duplicate_pad_numbers_are_jumpers no)
		(fp_rect
			(start 0.381 0.8382)
			(end -0.381 -0.8382)
			(stroke
				(width 0)
				(type default)
			)
			(fill no)
			(layer "B.CrtYd")
		)
		(fp_rect
			(start 0.381 0.8382)
			(end -0.381 -0.8382)
			(stroke
				(width 0)
				(type default)
			)
			(fill no)
			(layer "B.Fab")
		)
		(pad "1" smd custom
			(at 0 -0.4318 270)
			(size 0.127 0.127)
			(layers "B.Cu" "B.Mask" "B.Paste")
			(net "VR_PVNN_PHASE")
			(options
				(clearance outline)
				(anchor circle)
			)
			(primitives
				(gr_poly
					(pts
						(arc
							(start -0.2032 0.2794)
							(mid -0.239121 0.264521)
							(end -0.254 0.2286)
						)
						(arc
							(start -0.254 -0.2286)
							(mid -0.239121 -0.264521)
							(end -0.2032 -0.2794)
						)
						(arc
							(start 0.2032 -0.2794)
							(mid 0.239121 -0.264521)
							(end 0.254 -0.2286)
						)
						(arc
							(start 0.254 0.2286)
							(mid 0.239121 0.264521)
							(end 0.2032 0.2794)
						)
					)
					(width 0)
					(fill yes)
				)
			)
		)
		(pad "2" smd custom
			(at 0 0.4318 270)
			(size 0.127 0.127)
			(layers "B.Cu" "B.Mask" "B.Paste")
			(net "VR_PVNN_ISUMP_R2")
			(options
				(clearance outline)
				(anchor circle)
			)
			(primitives
				(gr_poly
					(pts
						(arc
							(start -0.2032 0.2794)
							(mid -0.239121 0.264521)
							(end -0.254 0.2286)
						)
						(arc
							(start -0.254 -0.2286)
							(mid -0.239121 -0.264521)
							(end -0.2032 -0.2794)
						)
						(arc
							(start 0.2032 -0.2794)
							(mid 0.239121 -0.264521)
							(end 0.254 -0.2286)
						)
						(arc
							(start 0.254 0.2286)
							(mid 0.239121 0.264521)
							(end 0.2032 0.2794)
						)
					)
					(width 0)
					(fill yes)
				)
			)
		)
	)
	(footprint ""
		(layer "B.Cu")
		(at 110.109 -5.715 180)
		(property "Reference" "R468"
			(at 0 0 0)
			(layer "B.SilkS")
			(hide yes)
			(effects
				(font
					(size 1.27 1.27)
				)
				(justify mirror)
			)
		)
		(property "Value" "8K2R2F-1-GP"
			(at -1.7907 -1.1176 180)
			(unlocked yes)
			(layer "B.Fab")
			(hide yes)
			(effects
				(font
					(size 1.016 1.016)
					(thickness 0.1524)
				)
				(justify mirror)
			)
		)
		(property "Device Type" "R402H16"
			(at -1.7907 -2.6416 180)
			(unlocked yes)
			(layer "B.Fab")
			(hide yes)
			(effects
				(font
					(size 1.016 1.016)
					(thickness 0.1524)
				)
				(justify mirror)
			)
		)
		(duplicate_pad_numbers_are_jumpers no)
		(fp_rect
			(start 0.381 0.8382)
			(end -0.381 -0.8382)
			(stroke
				(width 0)
				(type default)
			)
			(fill no)
			(layer "B.CrtYd")
		)
		(fp_rect
			(start 0.381 0.8382)
			(end -0.381 -0.8382)
			(stroke
				(width 0)
				(type default)
			)
			(fill no)
			(layer "B.Fab")
		)
		(pad "1" smd custom
			(at 0 -0.4318)
			(size 0.127 0.127)
			(layers "B.Cu" "B.Mask" "B.Paste")
			(net "P3V3_STBY")
			(options
				(clearance outline)
				(anchor circle)
			)
			(primitives
				(gr_poly
					(pts
						(arc
							(start -0.2032 0.2794)
							(mid -0.239121 0.264521)
							(end -0.254 0.2286)
						)
						(arc
							(start -0.254 -0.2286)
							(mid -0.239121 -0.264521)
							(end -0.2032 -0.2794)
						)
						(arc
							(start 0.2032 -0.2794)
							(mid 0.239121 -0.264521)
							(end 0.254 -0.2286)
						)
						(arc
							(start 0.254 0.2286)
							(mid 0.239121 0.264521)
							(end 0.2032 0.2794)
						)
					)
					(width 0)
					(fill yes)
				)
			)
		)
		(pad "2" smd custom
			(at 0 0.4318)
			(size 0.127 0.127)
			(layers "B.Cu" "B.Mask" "B.Paste")
			(net "IRQ_LV_MCERR#")
			(options
				(clearance outline)
				(anchor circle)
			)
			(primitives
				(gr_poly
					(pts
						(arc
							(start -0.2032 0.2794)
							(mid -0.239121 0.264521)
							(end -0.254 0.2286)
						)
						(arc
							(start -0.254 -0.2286)
							(mid -0.239121 -0.264521)
							(end -0.2032 -0.2794)
						)
						(arc
							(start 0.2032 -0.2794)
							(mid 0.239121 -0.264521)
							(end 0.254 -0.2286)
						)
						(arc
							(start 0.254 0.2286)
							(mid 0.239121 0.264521)
							(end 0.2032 0.2794)
						)
					)
					(width 0)
					(fill yes)
				)
			)
		)
	)
	(footprint ""
		(layer "B.Cu")
		(at 153.289 -36.068 -90)
		(property "Reference" "C234"
			(at 0 0 90)
			(layer "B.SilkS")
			(hide yes)
			(effects
				(font
					(size 1.27 1.27)
				)
				(justify mirror)
			)
		)
		(property "Value" "SCD1U10V2KX-5GP"
			(at -1.1811 -2.7051 270)
			(unlocked yes)
			(layer "B.Fab")
			(hide yes)
			(effects
				(font
					(size 1.016 1.016)
					(thickness 0.1524)
				)
				(justify mirror)
			)
		)
		(property "Device Type" "C402H22"
			(at -1.1811 -4.2291 270)
			(unlocked yes)
			(layer "B.Fab")
			(hide yes)
			(effects
				(font
					(size 1.016 1.016)
					(thickness 0.1524)
				)
				(justify mirror)
			)
		)
		(duplicate_pad_numbers_are_jumpers no)
		(fp_rect
			(start 0.381 0.7366)
			(end -0.381 -0.7366)
			(stroke
				(width 0)
				(type default)
			)
			(fill no)
			(layer "B.CrtYd")
		)
		(fp_rect
			(start 0.381 0.7366)
			(end -0.381 -0.7366)
			(stroke
				(width 0)
				(type default)
			)
			(fill no)
			(layer "B.Fab")
		)
		(pad "1" smd custom
			(at 0 -0.4572 90)
			(size 0.1143 0.1143)
			(layers "B.Cu" "B.Mask" "B.Paste")
			(net "P3V3_STBY")
			(options
				(clearance outline)
				(anchor circle)
			)
			(primitives
				(gr_poly
					(pts
						(arc
							(start -0.254 0.1778)
							(mid -0.239121 0.213721)
							(end -0.2032 0.2286)
						)
						(arc
							(start 0.2032 0.2286)
							(mid 0.239121 0.213721)
							(end 0.254 0.1778)
						)
						(arc
							(start 0.254 -0.1778)
							(mid 0.239121 -0.213721)
							(end 0.2032 -0.2286)
						)
						(arc
							(start -0.2032 -0.2286)
							(mid -0.239121 -0.213721)
							(end -0.254 -0.1778)
						)
					)
					(width 0)
					(fill yes)
				)
			)
		)
		(pad "2" smd custom
			(at 0 0.4572 90)
			(size 0.1143 0.1143)
			(layers "B.Cu" "B.Mask" "B.Paste")
			(net "GND")
			(options
				(clearance outline)
				(anchor circle)
			)
			(primitives
				(gr_poly
					(pts
						(arc
							(start -0.254 0.1778)
							(mid -0.239121 0.213721)
							(end -0.2032 0.2286)
						)
						(arc
							(start 0.2032 0.2286)
							(mid 0.239121 0.213721)
							(end 0.254 0.1778)
						)
						(arc
							(start 0.254 -0.1778)
							(mid 0.239121 -0.213721)
							(end 0.2032 -0.2286)
						)
						(arc
							(start -0.2032 -0.2286)
							(mid -0.239121 -0.213721)
							(end -0.254 -0.1778)
						)
					)
					(width 0)
					(fill yes)
				)
			)
		)
	)
	(footprint ""
		(layer "B.Cu")
		(at 72.6694 -20.1168)
		(property "Reference" "PC121"
			(at 0 0 0)
			(layer "B.SilkS")
			(hide yes)
			(effects
				(font
					(size 1.27 1.27)
				)
				(justify mirror)
			)
		)
		(property "Value" "SC680P50V2KX-2GP"
			(at -1.8923 -1.2065 0)
			(unlocked yes)
			(layer "B.Fab")
			(hide yes)
			(effects
				(font
					(size 1.016 1.016)
					(thickness 0.1524)
				)
				(justify mirror)
			)
		)
		(property "Device Type" "C402H22"
			(at -1.8923 -2.7305 0)
			(unlocked yes)
			(layer "B.Fab")
			(hide yes)
			(effects
				(font
					(size 1.016 1.016)
					(thickness 0.1524)
				)
				(justify mirror)
			)
		)
		(duplicate_pad_numbers_are_jumpers no)
		(fp_rect
			(start 0.381 0.7366)
			(end -0.381 -0.7366)
			(stroke
				(width 0)
				(type default)
			)
			(fill no)
			(layer "B.CrtYd")
		)
		(fp_rect
			(start 0.381 0.7366)
			(end -0.381 -0.7366)
			(stroke
				(width 0)
				(type default)
			)
			(fill no)
			(layer "B.Fab")
		)
		(pad "1" smd custom
			(at 0 -0.4572 180)
			(size 0.1143 0.1143)
			(layers "B.Cu" "B.Mask" "B.Paste")
			(net "VR_PVIN_P1V8_STBY")
			(options
				(clearance outline)
				(anchor circle)
			)
			(primitives
				(gr_poly
					(pts
						(arc
							(start -0.254 0.1778)
							(mid -0.239121 0.213721)
							(end -0.2032 0.2286)
						)
						(arc
							(start 0.2032 0.2286)
							(mid 0.239121 0.213721)
							(end 0.254 0.1778)
						)
						(arc
							(start 0.254 -0.1778)
							(mid 0.239121 -0.213721)
							(end 0.2032 -0.2286)
						)
						(arc
							(start -0.2032 -0.2286)
							(mid -0.239121 -0.213721)
							(end -0.254 -0.1778)
						)
					)
					(width 0)
					(fill yes)
				)
			)
		)
		(pad "2" smd custom
			(at 0 0.4572 180)
			(size 0.1143 0.1143)
			(layers "B.Cu" "B.Mask" "B.Paste")
			(net "GND")
			(options
				(clearance outline)
				(anchor circle)
			)
			(primitives
				(gr_poly
					(pts
						(arc
							(start -0.254 0.1778)
							(mid -0.239121 0.213721)
							(end -0.2032 0.2286)
						)
						(arc
							(start 0.2032 0.2286)
							(mid 0.239121 0.213721)
							(end 0.254 0.1778)
						)
						(arc
							(start 0.254 -0.1778)
							(mid 0.239121 -0.213721)
							(end 0.2032 -0.2286)
						)
						(arc
							(start -0.2032 -0.2286)
							(mid -0.239121 -0.213721)
							(end -0.254 -0.1778)
						)
					)
					(width 0)
					(fill yes)
				)
			)
		)
	)
	(footprint ""
		(layer "B.Cu")
		(at 36.957 -48.387 90)
		(property "Reference" "L2"
			(at 0 0 90)
			(layer "B.SilkS")
			(hide yes)
			(effects
				(font
					(size 1.27 1.27)
				)
				(justify mirror)
			)
		)
		(property "Value" "BLM18PG330SN1D-GP"
			(at 0.0254 -2.0193 90)
			(unlocked yes)
			(layer "B.Fab")
			(hide yes)
			(effects
				(font
					(size 1.016 1.016)
					(thickness 0.1524)
				)
				(justify mirror)
			)
		)
		(property "Device Type" "L1608-UH38"
			(at 0.0254 -3.5433 90)
			(unlocked yes)
			(layer "B.Fab")
			(hide yes)
			(effects
				(font
					(size 1.016 1.016)
					(thickness 0.1524)
				)
				(justify mirror)
			)
		)
		(duplicate_pad_numbers_are_jumpers no)
		(fp_line
			(start 0.4064 0)
			(end -0.4064 0)
			(stroke
				(width 0.2032)
				(type default)
			)
			(layer "B.SilkS")
		)
		(fp_rect
			(start 0.635 1.1811)
			(end -0.635 -1.1811)
			(stroke
				(width 0)
				(type default)
			)
			(fill no)
			(layer "B.CrtYd")
		)
		(fp_rect
			(start 0.635 1.1811)
			(end -0.635 -1.1811)
			(stroke
				(width 0)
				(type default)
			)
			(fill no)
			(layer "B.Fab")
		)
		(pad "1" smd custom
			(at 0 -0.6604 270)
			(size 0.19685 0.19685)
			(layers "B.Cu" "B.Mask" "B.Paste")
			(net "P3V3_STBY")
			(options
				(clearance outline)
				(anchor circle)
			)
			(primitives
				(gr_poly
					(pts
						(arc
							(start 0.508 0.2921)
							(mid 0.478242 0.363942)
							(end 0.4064 0.3937)
						)
						(arc
							(start -0.4064 0.3937)
							(mid -0.478242 0.363942)
							(end -0.508 0.2921)
						)
						(arc
							(start -0.508 -0.2921)
							(mid -0.478242 -0.363942)
							(end -0.4064 -0.3937)
						)
						(arc
							(start 0.4064 -0.3937)
							(mid 0.478242 -0.363942)
							(end 0.508 -0.2921)
						)
					)
					(width 0)
					(fill yes)
				)
			)
		)
		(pad "2" smd custom
			(at 0 0.6604 270)
			(size 0.19685 0.19685)
			(layers "B.Cu" "B.Mask" "B.Paste")
			(net "P3V3_CLK_XTAL")
			(options
				(clearance outline)
				(anchor circle)
			)
			(primitives
				(gr_poly
					(pts
						(arc
							(start 0.508 0.2921)
							(mid 0.478242 0.363942)
							(end 0.4064 0.3937)
						)
						(arc
							(start -0.4064 0.3937)
							(mid -0.478242 0.363942)
							(end -0.508 0.2921)
						)
						(arc
							(start -0.508 -0.2921)
							(mid -0.478242 -0.363942)
							(end -0.4064 -0.3937)
						)
						(arc
							(start 0.4064 -0.3937)
							(mid 0.478242 -0.363942)
							(end 0.508 -0.2921)
						)
					)
					(width 0)
					(fill yes)
				)
			)
		)
	)
	(footprint ""
		(layer "B.Cu")
		(at 44.6024 -15.5702 90)
		(property "Reference" "R427"
			(at 0 0 90)
			(layer "B.SilkS")
			(hide yes)
			(effects
				(font
					(size 1.27 1.27)
				)
				(justify mirror)
			)
		)
		(property "Value" "43D2R2F-GP"
			(at -1.7907 -1.1176 90)
			(unlocked yes)
			(layer "B.Fab")
			(hide yes)
			(effects
				(font
					(size 1.016 1.016)
					(thickness 0.1524)
				)
				(justify mirror)
			)
		)
		(property "Device Type" "R402H16"
			(at -1.7907 -2.6416 90)
			(unlocked yes)
			(layer "B.Fab")
			(hide yes)
			(effects
				(font
					(size 1.016 1.016)
					(thickness 0.1524)
				)
				(justify mirror)
			)
		)
		(duplicate_pad_numbers_are_jumpers no)
		(fp_rect
			(start 0.381 0.8382)
			(end -0.381 -0.8382)
			(stroke
				(width 0)
				(type default)
			)
			(fill no)
			(layer "B.CrtYd")
		)
		(fp_rect
			(start 0.381 0.8382)
			(end -0.381 -0.8382)
			(stroke
				(width 0)
				(type default)
			)
			(fill no)
			(layer "B.Fab")
		)
		(pad "1" smd custom
			(at 0 -0.4318 270)
			(size 0.127 0.127)
			(layers "B.Cu" "B.Mask" "B.Paste")
			(net "CLK_100M_CLKBUFF_ENET_DP")
			(options
				(clearance outline)
				(anchor circle)
			)
			(primitives
				(gr_poly
					(pts
						(arc
							(start -0.2032 0.2794)
							(mid -0.239121 0.264521)
							(end -0.254 0.2286)
						)
						(arc
							(start -0.254 -0.2286)
							(mid -0.239121 -0.264521)
							(end -0.2032 -0.2794)
						)
						(arc
							(start 0.2032 -0.2794)
							(mid 0.239121 -0.264521)
							(end 0.254 -0.2286)
						)
						(arc
							(start 0.254 0.2286)
							(mid 0.239121 0.264521)
							(end 0.2032 0.2794)
						)
					)
					(width 0)
					(fill yes)
				)
			)
		)
		(pad "2" smd custom
			(at 0 0.4318 270)
			(size 0.127 0.127)
			(layers "B.Cu" "B.Mask" "B.Paste")
			(net "GND")
			(options
				(clearance outline)
				(anchor circle)
			)
			(primitives
				(gr_poly
					(pts
						(arc
							(start -0.2032 0.2794)
							(mid -0.239121 0.264521)
							(end -0.254 0.2286)
						)
						(arc
							(start -0.254 -0.2286)
							(mid -0.239121 -0.264521)
							(end -0.2032 -0.2794)
						)
						(arc
							(start 0.2032 -0.2794)
							(mid 0.239121 -0.264521)
							(end 0.254 -0.2286)
						)
						(arc
							(start 0.254 0.2286)
							(mid 0.239121 0.264521)
							(end 0.2032 0.2794)
						)
					)
					(width 0)
					(fill yes)
				)
			)
		)
	)
)
